(kicad_pcb
	(version 20260206)
	(generator "pcbnew")
	(generator_version "10.0")
	(general
		(thickness 1.6)
		(legacy_teardrops no)
	)
	(paper "A4")
	(title_block
		(title "Wiwynn_Tioga_Pass_MB.brd")
		(comment 1 "Tioga Pass / footprint 190 of 4770 (U2D1), pads 1122-1228 of 3647")
	)
	(layers
		(0 "F.Cu" signal "TOP")
		(4 "In1.Cu" signal "L2GND")
		(6 "In2.Cu" signal "L3")
		(8 "In3.Cu" signal "L4GND")
		(10 "In4.Cu" signal "L5")
		(12 "In5.Cu" signal "L6GND")
		(14 "In6.Cu" signal "L7VCC")
		(16 "In7.Cu" signal "L8VCC")
		(18 "In8.Cu" signal "L9GND")
		(20 "In9.Cu" signal "L10")
		(22 "In10.Cu" signal "L11GND")
		(24 "In11.Cu" signal "L12")
		(26 "In12.Cu" signal "L13GND")
		(2 "B.Cu" signal "BOTTOM")
		(9 "F.Adhes" user "F.Adhesive")
		(11 "B.Adhes" user "B.Adhesive")
		(13 "F.Paste" user "Package Geometry/Pastemask Top")
		(15 "B.Paste" user "Package Geometry/Pastemask Bottom")
		(5 "F.SilkS" user "Ref Des/Silkscreen Top")
		(7 "B.SilkS" user "Ref Des/Silkscreen Bottom")
		(1 "F.Mask" user "Board Geometry/Soldermask Top")
		(3 "B.Mask" user "Board Geometry/Soldermask Bottom")
		(17 "Dwgs.User" user "User.Drawings")
		(19 "Cmts.User" user "User.Comments")
		(21 "Eco1.User" user "User.Eco1")
		(23 "Eco2.User" user "User.Eco2")
		(25 "Edge.Cuts" user "Board Geometry/Outline")
		(27 "Margin" user)
		(31 "F.CrtYd" user "Package Geometry/Place Bound Top")
		(29 "B.CrtYd" user "Package Geometry/Place Bound Bottom")
		(35 "F.Fab" user "Ref Des/Assembly Top")
		(33 "B.Fab" user "Ref Des/Assembly Bottom")
	)
	(footprint ""
		(layer "F.Cu")
		(at 104.99979 -76.550012 180)
		(property "Reference" "U2D1"
			(at 25.19299 30.484318 0)
			(unlocked yes)
			(layer "F.SilkS")
			(effects
				(font
					(size 0.7874 0.5842)
					(thickness 0.1524)
				)
			)
		)
		(property "Value" ""
			(at 0 0 180)
			(layer "F.Fab")
			(effects
				(font
					(size 1.27 1.27)
				)
			)
		)
		(duplicate_pad_numbers_are_jumpers no)
		(pad "BR20" smd circle
			(at -20.938998 1.643126)
			(size 0.4318 0.4318)
			(layers "F.Cu" "F.Mask" "F.Paste")
			(net "TP_FM_CPU1_CD_HFI0_MODPRST_N")
		)
		(pad "BR22" smd circle
			(at -19.221958 1.643126)
			(size 0.4318 0.4318)
			(layers "F.Cu" "F.Mask" "F.Paste")
			(net "PVCCMCP_CPU1")
		)
		(pad "BR24" smd circle
			(at -17.504918 1.643126)
			(size 0.4318 0.4318)
			(layers "F.Cu" "F.Mask" "F.Paste")
			(net "PVCCMCP_CPU1")
		)
		(pad "BR26" smd circle
			(at -15.787878 1.643126)
			(size 0.4318 0.4318)
			(layers "F.Cu" "F.Mask" "F.Paste")
			(net "GND")
		)
		(pad "BR60" smd circle
			(at 14.929612 -0.156972)
			(size 0.508 0.508)
			(layers "F.Cu" "F.Mask" "F.Paste")
			(net "PVCCIN_CPU1")
		)
		(pad "BR62" smd circle
			(at 16.646398 -0.156972)
			(size 0.4318 0.4318)
			(layers "F.Cu" "F.Mask" "F.Paste")
			(net "PVCCIN_CPU1")
		)
		(pad "BR64" smd circle
			(at 18.363438 -0.156972)
			(size 0.4318 0.4318)
			(layers "F.Cu" "F.Mask" "F.Paste")
			(net "GND")
		)
		(pad "BR66" smd circle
			(at 20.080478 -0.156972)
			(size 0.4318 0.4318)
			(layers "F.Cu" "F.Mask" "F.Paste")
			(net "GND")
		)
		(pad "BR68" smd circle
			(at 21.797518 -0.156972)
			(size 0.4318 0.4318)
			(layers "F.Cu" "F.Mask" "F.Paste")
			(net "GND")
		)
		(pad "BR70" smd circle
			(at 23.514558 -0.156972)
			(size 0.4318 0.4318)
			(layers "F.Cu" "F.Mask" "F.Paste")
			(net "GND")
		)
		(pad "BR72" smd circle
			(at 25.231598 -0.156972)
			(size 0.4318 0.4318)
			(layers "F.Cu" "F.Mask" "F.Paste")
			(net "GND")
		)
		(pad "BR74" smd circle
			(at 26.948384 -0.156972)
			(size 0.4318 0.4318)
			(layers "F.Cu" "F.Mask" "F.Paste")
			(net "GND")
		)
		(pad "BR76" smd circle
			(at 28.665424 -0.156972)
			(size 0.4318 0.4318)
			(layers "F.Cu" "F.Mask" "F.Paste")
			(net "GND")
		)
		(pad "BR78" smd circle
			(at 30.382464 -0.156972)
			(size 0.4318 0.4318)
			(layers "F.Cu" "F.Mask" "F.Paste")
			(net "GND")
		)
		(pad "BR80" smd circle
			(at 32.099504 -0.156972)
			(size 0.4318 0.4318)
			(layers "F.Cu" "F.Mask" "F.Paste")
			(net "GND")
		)
		(pad "BR82" smd circle
			(at 33.816544 -0.156972)
			(size 0.4318 0.4318)
			(layers "F.Cu" "F.Mask" "F.Paste")
			(net "GND")
		)
		(pad "BR84" smd custom
			(at 35.533584 -0.156972 270)
			(size 0.10795 0.10795)
			(layers "F.Cu" "F.Mask" "F.Paste")
			(net "PVCCIN_CPU1")
			(options
				(clearance outline)
				(anchor circle)
			)
			(primitives
				(gr_poly
					(pts
						(arc
							(start 0.2159 -0.0381)
							(mid 0 -0.254)
							(end -0.2159 -0.0381)
						)
						(arc
							(start -0.2159 0.0381)
							(mid 0 0.254)
							(end 0.2159 0.0381)
						)
					)
					(width 0)
					(fill yes)
				)
			)
		)
		(pad "BT3" smd custom
			(at -35.533584 2.138426 90)
			(size 0.10795 0.10795)
			(layers "F.Cu" "F.Mask" "F.Paste")
			(net "GND")
			(options
				(clearance outline)
				(anchor circle)
			)
			(primitives
				(gr_poly
					(pts
						(arc
							(start 0.2159 -0.0381)
							(mid 0 -0.254)
							(end -0.2159 -0.0381)
						)
						(arc
							(start -0.2159 0.0381)
							(mid 0 0.254)
							(end 0.2159 0.0381)
						)
					)
					(width 0)
					(fill yes)
				)
			)
		)
		(pad "BT5" smd circle
			(at -33.816544 2.138426)
			(size 0.4318 0.4318)
			(layers "F.Cu" "F.Mask" "F.Paste")
			(net "GND")
		)
		(pad "BT7" smd circle
			(at -32.099504 2.138426)
			(size 0.4318 0.4318)
			(layers "F.Cu" "F.Mask" "F.Paste")
			(net "TP_P3E_CPU1_PE2_RSR_RXN<11>")
		)
		(pad "BT9" smd circle
			(at -30.382464 2.138426)
			(size 0.4318 0.4318)
			(layers "F.Cu" "F.Mask" "F.Paste")
			(net "GND")
		)
		(pad "BT11" smd circle
			(at -28.665424 2.138426)
			(size 0.4318 0.4318)
			(layers "F.Cu" "F.Mask" "F.Paste")
			(net "PVCCIOMCP_CPU1")
		)
		(pad "BT13" smd circle
			(at -26.948384 2.138426)
			(size 0.4318 0.4318)
			(layers "F.Cu" "F.Mask" "F.Paste")
			(net "PVCCIOMCP_CPU1")
		)
		(pad "BT15" smd circle
			(at -25.231598 2.138426)
			(size 0.4318 0.4318)
			(layers "F.Cu" "F.Mask" "F.Paste")
			(net "PVCCIOMCP_CPU1")
		)
		(pad "BT17" smd circle
			(at -23.514558 2.138426)
			(size 0.4318 0.4318)
			(layers "F.Cu" "F.Mask" "F.Paste")
			(net "VSENSE_PVCCIOMCP_CPU1_SKT_VSEN")
		)
		(pad "BT19" smd circle
			(at -21.797518 2.138426)
			(size 0.4318 0.4318)
			(layers "F.Cu" "F.Mask" "F.Paste")
			(net "TP_CD_HFI1_CPU1_MODPRST_N")
		)
		(pad "BT21" smd circle
			(at -20.080478 2.138426)
			(size 0.4318 0.4318)
			(layers "F.Cu" "F.Mask" "F.Paste")
			(net "GND")
		)
		(pad "BT23" smd circle
			(at -18.363438 2.138426)
			(size 0.4318 0.4318)
			(layers "F.Cu" "F.Mask" "F.Paste")
			(net "GND")
		)
		(pad "BT25" smd circle
			(at -16.646398 2.138426)
			(size 0.4318 0.4318)
			(layers "F.Cu" "F.Mask" "F.Paste")
			(net "GND")
		)
		(pad "BT27" smd circle
			(at -14.929612 2.138426)
			(size 0.4318 0.4318)
			(layers "F.Cu" "F.Mask" "F.Paste")
			(net "P1V8_MCP_CPU1")
		)
		(pad "BT61" smd circle
			(at 15.787878 0.338074)
			(size 0.4318 0.4318)
			(layers "F.Cu" "F.Mask" "F.Paste")
			(net "PVCCIN_CPU1")
		)
		(pad "BT63" smd circle
			(at 17.504918 0.338074)
			(size 0.4318 0.4318)
			(layers "F.Cu" "F.Mask" "F.Paste")
			(net "PVCCIN_CPU1")
		)
		(pad "BT65" smd circle
			(at 19.221958 0.338074)
			(size 0.4318 0.4318)
			(layers "F.Cu" "F.Mask" "F.Paste")
			(net "PVCCIN_CPU1")
		)
		(pad "BT67" smd circle
			(at 20.938998 0.338074)
			(size 0.4318 0.4318)
			(layers "F.Cu" "F.Mask" "F.Paste")
			(net "PVCCIN_CPU1")
		)
		(pad "BT69" smd circle
			(at 22.656038 0.338074)
			(size 0.4318 0.4318)
			(layers "F.Cu" "F.Mask" "F.Paste")
			(net "PVCCIN_CPU1")
		)
		(pad "BT71" smd circle
			(at 24.373078 0.338074)
			(size 0.4318 0.4318)
			(layers "F.Cu" "F.Mask" "F.Paste")
			(net "PVCCIN_CPU1")
		)
		(pad "BT73" smd circle
			(at 26.090118 0.338074)
			(size 0.4318 0.4318)
			(layers "F.Cu" "F.Mask" "F.Paste")
			(net "PVCCIN_CPU1")
		)
		(pad "BT75" smd circle
			(at 27.806904 0.338074)
			(size 0.4318 0.4318)
			(layers "F.Cu" "F.Mask" "F.Paste")
			(net "PVCCIN_CPU1")
		)
		(pad "BT77" smd circle
			(at 29.523944 0.338074)
			(size 0.4318 0.4318)
			(layers "F.Cu" "F.Mask" "F.Paste")
			(net "PVCCIN_CPU1")
		)
		(pad "BT79" smd circle
			(at 31.240984 0.338074)
			(size 0.4318 0.4318)
			(layers "F.Cu" "F.Mask" "F.Paste")
			(net "PVCCIN_CPU1")
		)
		(pad "BT81" smd circle
			(at 32.958024 0.338074)
			(size 0.4318 0.4318)
			(layers "F.Cu" "F.Mask" "F.Paste")
			(net "PVCCIN_CPU1")
		)
		(pad "BT83" smd circle
			(at 34.675064 0.338074)
			(size 0.4318 0.4318)
			(layers "F.Cu" "F.Mask" "F.Paste")
			(net "PVCCIN_CPU1")
		)
		(pad "BU4" smd circle
			(at -34.675064 2.633726)
			(size 0.4318 0.4318)
			(layers "F.Cu" "F.Mask" "F.Paste")
			(net "TP_P3E_CPU1_PE2_RSR_TXN<12>")
		)
		(pad "BU6" smd circle
			(at -32.958024 2.633726)
			(size 0.4318 0.4318)
			(layers "F.Cu" "F.Mask" "F.Paste")
			(net "TP_P3E_CPU1_PE2_RSR_RXP<10>")
		)
		(pad "BU8" smd circle
			(at -31.240984 2.633726)
			(size 0.4318 0.4318)
			(layers "F.Cu" "F.Mask" "F.Paste")
			(net "GND")
		)
		(pad "BU10" smd circle
			(at -29.523944 2.633726)
			(size 0.4318 0.4318)
			(layers "F.Cu" "F.Mask" "F.Paste")
			(net "GND")
		)
		(pad "BU12" smd circle
			(at -27.806904 2.633726)
			(size 0.4318 0.4318)
			(layers "F.Cu" "F.Mask" "F.Paste")
			(net "PVCCIOMCP_CPU1")
		)
		(pad "BU14" smd circle
			(at -26.090118 2.633726)
			(size 0.4318 0.4318)
			(layers "F.Cu" "F.Mask" "F.Paste")
			(net "PVCCIOMCP_CPU1")
		)
		(pad "BU16" smd circle
			(at -24.373078 2.633726)
			(size 0.4318 0.4318)
			(layers "F.Cu" "F.Mask" "F.Paste")
			(net "VSENSE_PVCCIOMCP_CPU1_SKT_VRTN")
		)
		(pad "BU18" smd circle
			(at -22.656038 2.633726)
			(size 0.4318 0.4318)
			(layers "F.Cu" "F.Mask" "F.Paste")
			(net "PVCCIOMCP_CPU1")
		)
		(pad "BU20" smd circle
			(at -20.938998 2.633726)
			(size 0.4318 0.4318)
			(layers "F.Cu" "F.Mask" "F.Paste")
			(net "PVCCMCP_CPU1")
		)
		(pad "BU22" smd circle
			(at -19.221958 2.633726)
			(size 0.4318 0.4318)
			(layers "F.Cu" "F.Mask" "F.Paste")
			(net "PVCCMCP_CPU1")
		)
		(pad "BU24" smd circle
			(at -17.504918 2.633726)
			(size 0.4318 0.4318)
			(layers "F.Cu" "F.Mask" "F.Paste")
			(net "CLK_100M_CPU1_PE_REFCLK_DN")
		)
		(pad "BU26" smd circle
			(at -15.787878 2.633726)
			(size 0.4318 0.4318)
			(layers "F.Cu" "F.Mask" "F.Paste")
			(net "P1V8_MCP_CPU1")
		)
		(pad "BU60" smd circle
			(at 14.929612 0.833628)
			(size 0.508 0.508)
			(layers "F.Cu" "F.Mask" "F.Paste")
			(net "PVCCIN_CPU1")
		)
		(pad "BU62" smd circle
			(at 16.646398 0.833628)
			(size 0.4318 0.4318)
			(layers "F.Cu" "F.Mask" "F.Paste")
			(net "PVCCIN_CPU1")
		)
		(pad "BU64" smd circle
			(at 18.363438 0.833628)
			(size 0.4318 0.4318)
			(layers "F.Cu" "F.Mask" "F.Paste")
			(net "PVCCIN_CPU1")
		)
		(pad "BU66" smd circle
			(at 20.080478 0.833628)
			(size 0.4318 0.4318)
			(layers "F.Cu" "F.Mask" "F.Paste")
			(net "PVCCIN_CPU1")
		)
		(pad "BU68" smd circle
			(at 21.797518 0.833628)
			(size 0.4318 0.4318)
			(layers "F.Cu" "F.Mask" "F.Paste")
			(net "PVCCIN_CPU1")
		)
		(pad "BU70" smd circle
			(at 23.514558 0.833628)
			(size 0.4318 0.4318)
			(layers "F.Cu" "F.Mask" "F.Paste")
			(net "PVCCIN_CPU1")
		)
		(pad "BU72" smd circle
			(at 25.231598 0.833628)
			(size 0.4318 0.4318)
			(layers "F.Cu" "F.Mask" "F.Paste")
			(net "PVCCIN_CPU1")
		)
		(pad "BU74" smd circle
			(at 26.948384 0.833628)
			(size 0.4318 0.4318)
			(layers "F.Cu" "F.Mask" "F.Paste")
			(net "PVCCIN_CPU1")
		)
		(pad "BU76" smd circle
			(at 28.665424 0.833628)
			(size 0.4318 0.4318)
			(layers "F.Cu" "F.Mask" "F.Paste")
			(net "PVCCIN_CPU1")
		)
		(pad "BU78" smd circle
			(at 30.382464 0.833628)
			(size 0.4318 0.4318)
			(layers "F.Cu" "F.Mask" "F.Paste")
			(net "PVCCIN_CPU1")
		)
		(pad "BU80" smd circle
			(at 32.099504 0.833628)
			(size 0.4318 0.4318)
			(layers "F.Cu" "F.Mask" "F.Paste")
			(net "PVCCIN_CPU1")
		)
		(pad "BU82" smd circle
			(at 33.816544 0.833628)
			(size 0.4318 0.4318)
			(layers "F.Cu" "F.Mask" "F.Paste")
			(net "PVCCIN_CPU1")
		)
		(pad "BU84" smd custom
			(at 35.533584 0.833628 270)
			(size 0.10795 0.10795)
			(layers "F.Cu" "F.Mask" "F.Paste")
			(net "PVCCIN_CPU1")
			(options
				(clearance outline)
				(anchor circle)
			)
			(primitives
				(gr_poly
					(pts
						(arc
							(start 0.2159 -0.0381)
							(mid 0 -0.254)
							(end -0.2159 -0.0381)
						)
						(arc
							(start -0.2159 0.0381)
							(mid 0 0.254)
							(end 0.2159 0.0381)
						)
					)
					(width 0)
					(fill yes)
				)
			)
		)
		(pad "BV3" smd custom
			(at -35.533584 3.128772 90)
			(size 0.10795 0.10795)
			(layers "F.Cu" "F.Mask" "F.Paste")
			(net "TP_P3E_CPU1_PE2_RSR_TXP<11>")
			(options
				(clearance outline)
				(anchor circle)
			)
			(primitives
				(gr_poly
					(pts
						(arc
							(start 0.2159 -0.0381)
							(mid 0 -0.254)
							(end -0.2159 -0.0381)
						)
						(arc
							(start -0.2159 0.0381)
							(mid 0 0.254)
							(end 0.2159 0.0381)
						)
					)
					(width 0)
					(fill yes)
				)
			)
		)
		(pad "BV5" smd circle
			(at -33.816544 3.128772)
			(size 0.4318 0.4318)
			(layers "F.Cu" "F.Mask" "F.Paste")
			(net "GND")
		)
		(pad "BV7" smd circle
			(at -32.099504 3.128772)
			(size 0.4318 0.4318)
			(layers "F.Cu" "F.Mask" "F.Paste")
			(net "TP_P3E_CPU1_PE2_RSR_RXN<10>")
		)
		(pad "BV9" smd circle
			(at -30.382464 3.128772)
			(size 0.4318 0.4318)
			(layers "F.Cu" "F.Mask" "F.Paste")
			(net "TP_P3E_CPU1_PE2_RSR_RXP<8>")
		)
		(pad "BV11" smd circle
			(at -28.665424 3.128772)
			(size 0.4318 0.4318)
			(layers "F.Cu" "F.Mask" "F.Paste")
			(net "PVCCIOMCP_CPU1")
		)
		(pad "BV13" smd circle
			(at -26.948384 3.128772)
			(size 0.4318 0.4318)
			(layers "F.Cu" "F.Mask" "F.Paste")
			(net "PVCCIOMCP_CPU1")
		)
		(pad "BV15" smd circle
			(at -25.231598 3.128772)
			(size 0.4318 0.4318)
			(layers "F.Cu" "F.Mask" "F.Paste")
			(net "PVCCIOMCP_CPU1")
		)
		(pad "BV17" smd circle
			(at -23.514558 3.128772)
			(size 0.4318 0.4318)
			(layers "F.Cu" "F.Mask" "F.Paste")
			(net "GND")
		)
		(pad "BV19" smd circle
			(at -21.797518 3.128772)
			(size 0.4318 0.4318)
			(layers "F.Cu" "F.Mask" "F.Paste")
			(net "PVCCMCP_CPU1")
		)
		(pad "BV21" smd circle
			(at -20.080478 3.128772)
			(size 0.4318 0.4318)
			(layers "F.Cu" "F.Mask" "F.Paste")
			(net "PVCCMCP_CPU1")
		)
		(pad "BV23" smd circle
			(at -18.363438 3.128772)
			(size 0.4318 0.4318)
			(layers "F.Cu" "F.Mask" "F.Paste")
			(net "TP_CPU1_RSVD_124")
		)
		(pad "BV25" smd circle
			(at -16.646398 3.128772)
			(size 0.4318 0.4318)
			(layers "F.Cu" "F.Mask" "F.Paste")
			(net "GND")
		)
		(pad "BV27" smd circle
			(at -14.929612 3.128772)
			(size 0.4318 0.4318)
			(layers "F.Cu" "F.Mask" "F.Paste")
			(net "P1V8_MCP_CPU1")
		)
		(pad "BV61" smd circle
			(at 15.787878 1.328674)
			(size 0.4318 0.4318)
			(layers "F.Cu" "F.Mask" "F.Paste")
			(net "PVCCIN_CPU1")
		)
		(pad "BV63" smd circle
			(at 17.504918 1.328674)
			(size 0.4318 0.4318)
			(layers "F.Cu" "F.Mask" "F.Paste")
			(net "PVCCIN_CPU1")
		)
		(pad "BV65" smd circle
			(at 19.221958 1.328674)
			(size 0.4318 0.4318)
			(layers "F.Cu" "F.Mask" "F.Paste")
			(net "PVCCIN_CPU1")
		)
		(pad "BV67" smd circle
			(at 20.938998 1.328674)
			(size 0.4318 0.4318)
			(layers "F.Cu" "F.Mask" "F.Paste")
			(net "PVCCIN_CPU1")
		)
		(pad "BV69" smd circle
			(at 22.656038 1.328674)
			(size 0.4318 0.4318)
			(layers "F.Cu" "F.Mask" "F.Paste")
			(net "PVCCIN_CPU1")
		)
		(pad "BV71" smd circle
			(at 24.373078 1.328674)
			(size 0.4318 0.4318)
			(layers "F.Cu" "F.Mask" "F.Paste")
			(net "PVCCIN_CPU1")
		)
		(pad "BV73" smd circle
			(at 26.090118 1.328674)
			(size 0.4318 0.4318)
			(layers "F.Cu" "F.Mask" "F.Paste")
			(net "PVCCIN_CPU1")
		)
		(pad "BV75" smd circle
			(at 27.806904 1.328674)
			(size 0.4318 0.4318)
			(layers "F.Cu" "F.Mask" "F.Paste")
			(net "PVCCIN_CPU1")
		)
		(pad "BV77" smd circle
			(at 29.523944 1.328674)
			(size 0.4318 0.4318)
			(layers "F.Cu" "F.Mask" "F.Paste")
			(net "PVCCIN_CPU1")
		)
		(pad "BV79" smd circle
			(at 31.240984 1.328674)
			(size 0.4318 0.4318)
			(layers "F.Cu" "F.Mask" "F.Paste")
			(net "PVCCIN_CPU1")
		)
		(pad "BV81" smd circle
			(at 32.958024 1.328674)
			(size 0.4318 0.4318)
			(layers "F.Cu" "F.Mask" "F.Paste")
			(net "PVCCIN_CPU1")
		)
		(pad "BV83" smd circle
			(at 34.675064 1.328674)
			(size 0.4318 0.4318)
			(layers "F.Cu" "F.Mask" "F.Paste")
			(net "PVCCIN_CPU1")
		)
		(pad "BW4" smd circle
			(at -34.675064 3.624326)
			(size 0.4318 0.4318)
			(layers "F.Cu" "F.Mask" "F.Paste")
			(net "TP_P3E_CPU1_PE2_RSR_TXN<11>")
		)
		(pad "BW6" smd circle
			(at -32.958024 3.624326)
			(size 0.4318 0.4318)
			(layers "F.Cu" "F.Mask" "F.Paste")
			(net "GND")
		)
		(pad "BW8" smd circle
			(at -31.240984 3.624326)
			(size 0.4318 0.4318)
			(layers "F.Cu" "F.Mask" "F.Paste")
			(net "TP_P3E_CPU1_PE2_RSR_RXP<9>")
		)
		(pad "BW10" smd circle
			(at -29.523944 3.624326)
			(size 0.4318 0.4318)
			(layers "F.Cu" "F.Mask" "F.Paste")
			(net "TP_CPU1_RSVD_123")
		)
		(pad "BW12" smd circle
			(at -27.806904 3.624326)
			(size 0.4318 0.4318)
			(layers "F.Cu" "F.Mask" "F.Paste")
			(net "GND")
		)
		(pad "BW14" smd circle
			(at -26.090118 3.624326)
			(size 0.4318 0.4318)
			(layers "F.Cu" "F.Mask" "F.Paste")
			(net "GND")
		)
		(pad "BW16" smd circle
			(at -24.373078 3.624326)
			(size 0.4318 0.4318)
			(layers "F.Cu" "F.Mask" "F.Paste")
			(net "GND")
		)
		(pad "BW18" smd circle
			(at -22.656038 3.624326)
			(size 0.4318 0.4318)
			(layers "F.Cu" "F.Mask" "F.Paste")
			(net "GND")
		)
		(pad "BW20" smd circle
			(at -20.938998 3.624326)
			(size 0.4318 0.4318)
			(layers "F.Cu" "F.Mask" "F.Paste")
			(net "PVCCMCP_CPU1")
		)
		(pad "BW22" smd circle
			(at -19.221958 3.624326)
			(size 0.4318 0.4318)
			(layers "F.Cu" "F.Mask" "F.Paste")
			(net "TP_CPU1_RSVD_121")
		)
		(pad "BW24" smd circle
			(at -17.504918 3.624326)
			(size 0.4318 0.4318)
			(layers "F.Cu" "F.Mask" "F.Paste")
			(net "CLK_100M_CPU1_PE_REFCLK_DP")
		)
		(pad "BW26" smd circle
			(at -15.787878 3.624326)
			(size 0.4318 0.4318)
			(layers "F.Cu" "F.Mask" "F.Paste")
			(net "GND")
		)
		(pad "BW60" smd circle
			(at 14.929612 1.824228)
			(size 0.508 0.508)
			(layers "F.Cu" "F.Mask" "F.Paste")
			(net "PVCCIN_CPU1")
		)
		(pad "BW62" smd circle
			(at 16.646398 1.824228)
			(size 0.4318 0.4318)
			(layers "F.Cu" "F.Mask" "F.Paste")
			(net "PVCCIN_CPU1")
		)
		(pad "BW64" smd circle
			(at 18.363438 1.824228)
			(size 0.4318 0.4318)
			(layers "F.Cu" "F.Mask" "F.Paste")
			(net "PVCCIN_CPU1")
		)
	)
)
